G04 ================== begin FILE IDENTIFICATION RECORD ==================*
G04 Layout Name:  16368-sb.brd*
G04 Film Name:    BSILK*
G04 File Format:  Gerber RS274X*
G04 File Origin:  Cadence Allegro 16.5-S056*
G04 Origin Date:  Tue Feb 07 09:07:39 2017*
G04 *
G04 Layer:  VIA CLASS/FILMMASKBOTTOM*
G04 Layer:  REF DES/ASSEMBLY_BOTTOM*
G04 Layer:  PACKAGE GEOMETRY/SILKSCREEN_BOTTOM*
G04 Layer:  DRAWING FORMAT/LAYER_PCB_STORY*
G04 Layer:  DRAWING FORMAT/LAYER_SILK_B*
G04 Layer:  BOARD GEOMETRY/SILKSCREEN_BOTTOM*
G04 *
G04 Offset:    (0.00 0.00)*
G04 Mirror:    No*
G04 Mode:      Positive*
G04 Rotation:  0*
G04 FullContactRelief:  No*
G04 UndefLineWidth:     6.00*
G04 ================== end FILE IDENTIFICATION RECORD ====================*
%FSLAX35Y35*MOIN*%
%IR0*IPPOS*OFA0.00000B0.00000*MIA0B0*SFA1.00000B1.00000*%
%ADD10C,.02*%
%ADD11C,.012*%
%ADD12C,.013*%
%ADD13C,.006*%
%ADD14C,.008*%
G75*
%LPD*%
G75*
G36*
G01X58035Y24242D02*
Y20742D01*
X42558D01*
Y10053D01*
X103112D01*
Y20742D01*
X87635D01*
Y24242D01*
X58035D01*
G37*
G36*
G01X100467Y1656D02*
X102967Y-844D01*
X97967D01*
X100467Y1656D01*
G37*
G36*
G01X97753Y46064D02*
X100853D01*
Y41732D01*
X97753D01*
Y46064D01*
G37*
G36*
G01X106453D02*
X124453D01*
Y41732D01*
X106453D01*
Y46064D01*
G37*
G36*
G01X99744Y59048D02*
X97244Y61548D01*
X102244D01*
X99744Y59048D01*
G37*
G36*
G01X125850Y14760D02*
X124650Y13560D01*
X125850Y12360D01*
Y14760D01*
G37*
G36*
G01X133153Y46064D02*
X130053D01*
Y41732D01*
X133153D01*
Y46064D01*
G37*
G54D10*
G01X-149983Y-76117D02*
Y-156117D01*
G01D02*
X864117D01*
G01X-153983Y-60117D02*
G02I-12000J0D01*
G01X-159133D02*
G02I-6850J0D01*
G01X-165983Y-76117D02*
Y-44117D01*
G01X-149983Y-60117D02*
X-181983D01*
G01X-149983Y-76117D02*
X864117D01*
G01X-149983Y-111617D02*
X864117D01*
G01X76617Y-76117D02*
Y-156117D01*
G01X119400Y24000D02*
Y18000D01*
G01X214117Y-76117D02*
Y-156117D01*
G01X329117Y-76117D02*
Y-156117D01*
G01X496617Y-76117D02*
Y-156117D01*
G01X666617Y-76117D02*
Y-156117D01*
G01X864117Y-76117D02*
Y-156117D01*
G01X892117Y-60117D02*
G02I-12000J0D01*
G01X886967D02*
G02I-6850J0D01*
G01X880117Y-76117D02*
Y-44117D01*
G01X896117Y-60117D02*
X864117D01*
G54D11*
G01X11811Y0D02*
X37008D01*
G01X11811Y69685D02*
X37008D01*
G01X11811Y61811D02*
X37008D01*
G01X11811Y139370D02*
X37008D01*
G01X11811Y131496D02*
X37008D01*
G01X11811Y209055D02*
X37008D01*
G01X11811Y201181D02*
X37008D01*
G01X11811Y278740D02*
X37008D01*
G01X11811Y270866D02*
X37008D01*
G01X11811Y348425D02*
X37008D01*
G01X11811Y340551D02*
X37008D01*
G01Y418110D02*
X11811D01*
G01X37008Y410236D02*
X11811D01*
G01Y487795D02*
X37008D01*
G01X11811Y479921D02*
X37008D01*
G01X11811Y557480D02*
X37008D01*
G01X11811Y549606D02*
X37008D01*
G01X11811Y627165D02*
X37008D01*
G01X11811Y619291D02*
X37008D01*
G01X185040Y43504D02*
Y18307D01*
G01X177166Y43504D02*
Y18307D01*
G01X140158Y0D02*
X165355D01*
G01X196851D02*
X222048D01*
G01X140158Y69685D02*
X165355D01*
G01X140158Y61811D02*
X165355D01*
G01X177166Y113189D02*
Y87992D01*
G01X185040Y113189D02*
Y87992D01*
G01X196851Y139370D02*
X222048D01*
G01X196851Y131496D02*
X222048D01*
G01X140158Y139370D02*
X165355D01*
G01X140158Y131496D02*
X165355D01*
G01X177166Y182874D02*
Y157677D01*
G01X185040Y182874D02*
Y157677D01*
G01X140158Y209055D02*
X165355D01*
G01X140158Y201181D02*
X165355D01*
G01X177166Y227362D02*
Y252559D01*
G01X185040Y227362D02*
Y252559D01*
G01X196851Y209055D02*
X222048D01*
G01X196851Y201181D02*
X222048D01*
G01X196851Y278740D02*
X222048D01*
G01X196851Y270866D02*
X222048D01*
G01X140158Y278740D02*
X165355D01*
G01X140158Y270866D02*
X165355D01*
G01X177166Y322244D02*
Y297047D01*
G01X185040Y322244D02*
Y297047D01*
G01X140158Y348425D02*
X165355D01*
G01X140158Y340551D02*
X165355D01*
G01X196851Y348425D02*
X222048D01*
G01X196851Y340551D02*
X222048D01*
G01X177166Y391929D02*
Y366732D01*
G01X185040Y391929D02*
Y366732D01*
G01X222048Y418110D02*
X196851D01*
G01X222048Y410236D02*
X196851D01*
G01X140158Y418110D02*
X165355D01*
G01X140158Y410236D02*
X165355D01*
G01X177166Y461614D02*
Y436417D01*
G01X185040Y461614D02*
Y436417D01*
G01X140158Y487795D02*
X165355D01*
G01X140158Y479921D02*
X165355D01*
G01X177166Y531299D02*
Y506102D01*
G01X185040Y531299D02*
Y506102D01*
G01X222048Y487795D02*
X196851D01*
G01X222048Y479921D02*
X196851D01*
G01X177166Y600984D02*
Y575787D01*
G01X185040Y600984D02*
Y575787D01*
G01X140158Y557480D02*
X165355D01*
G01X140158Y549606D02*
X165355D01*
G01X196851Y557480D02*
X222048D01*
G01X196851Y549606D02*
X222048D01*
G01X196851Y627165D02*
X222048D01*
G01X196851Y619291D02*
X222048D01*
G01X177166Y670669D02*
Y645472D01*
G01X185040Y670669D02*
Y645472D01*
G01X165355Y627165D02*
X140158D01*
G01X165355Y619291D02*
X140158D01*
G01X325197Y0D02*
X350394D01*
G01X362205Y43504D02*
Y18307D01*
G01X325197Y69685D02*
X350394D01*
G01X325197Y61811D02*
X350394D01*
G01X362205Y113189D02*
Y87992D01*
G01X325197Y139370D02*
X350394D01*
G01X325197Y131496D02*
X350394D01*
G01X362205Y182874D02*
Y157677D01*
G01X350394Y209055D02*
X325197D01*
G01X350394Y201181D02*
X325197D01*
G01X362205Y252559D02*
Y227362D01*
G01X325197Y278740D02*
X350394D01*
G01X325197Y270866D02*
X350394D01*
G01X362205Y322244D02*
Y297047D01*
G01X325197Y348425D02*
X350394D01*
G01X325197Y340551D02*
X350394D01*
G01X362205Y391929D02*
Y366732D01*
G01Y461614D02*
Y436417D01*
G01X325197Y418110D02*
X350394D01*
G01X325197Y410236D02*
X350394D01*
G01X325197Y487795D02*
X350394D01*
G01X325197Y479921D02*
X350394D01*
G01X362205Y531299D02*
Y506102D01*
G01Y600984D02*
Y575787D01*
G01X325197Y557480D02*
X350394D01*
G01X325197Y549606D02*
X350394D01*
G01X362205Y670669D02*
Y645472D01*
G01X350394Y627165D02*
X325197D01*
G01X350394Y619291D02*
X325197D01*
G01X370079Y43504D02*
Y18307D01*
G01X381890Y0D02*
X407087D01*
G01X381890Y69685D02*
X407087D01*
G01X381890Y61811D02*
X407087D01*
G01X370079Y113189D02*
Y87992D01*
G01X381890Y139370D02*
X407087D01*
G01X381890Y131496D02*
X407087D01*
G01X370079Y182874D02*
Y157677D01*
G01Y252559D02*
Y227362D01*
G01X381890Y209055D02*
X407087D01*
G01X381890Y201181D02*
X407087D01*
G01X381890Y278740D02*
X407087D01*
G01X381890Y270866D02*
X407087D01*
G01X370079Y322244D02*
Y297047D01*
G01X407087Y348425D02*
X381890D01*
G01X407087Y340551D02*
X381890D01*
G01X370079Y391929D02*
Y366732D01*
G01X381890Y418110D02*
X407087D01*
G01X381890Y410236D02*
X407087D01*
G01X370079Y461614D02*
Y436417D01*
G01X381890Y487795D02*
X407087D01*
G01X381890Y479921D02*
X407087D01*
G01X370079Y531299D02*
Y506102D01*
G01X407087Y557480D02*
X381890D01*
G01X407087Y549606D02*
X381890D01*
G01X370079Y600984D02*
Y575787D01*
G01X381890Y627165D02*
X407087D01*
G01X381890Y619291D02*
X407087D01*
G01X370079Y670669D02*
Y645472D01*
G01X510237Y0D02*
X535433D01*
G01X510237Y69685D02*
X535433D01*
G01X510237Y61811D02*
X535433D01*
G01X510237Y139370D02*
X535433D01*
G01X510237Y131496D02*
X535433D01*
G01X510237Y209055D02*
X535433D01*
G01X510237Y201181D02*
X535433D01*
G01X510237Y278740D02*
X535433D01*
G01X510237Y270866D02*
X535433D01*
G01Y348425D02*
X510237D01*
G01X535433Y340551D02*
X510237D01*
G01Y418110D02*
X535433D01*
G01X510237Y410236D02*
X535433D01*
G01X510237Y487795D02*
X535433D01*
G01X510237Y479921D02*
X535433D01*
G01X510237Y557480D02*
X535433D01*
G01X510237Y549606D02*
X535433D01*
G01X510237Y627165D02*
X535433D01*
G01X510237Y619291D02*
X535433D01*
G54D12*
G01X98685Y1592D02*
X102185D01*
G01X85100Y27400D02*
X87950D01*
Y30100D01*
G01X97603Y59048D02*
X101703D01*
G01X79900Y57100D02*
X77050D01*
Y54400D01*
G54D13*
G01X-137600Y-128617D02*
Y-146117D01*
X-128866D01*
G01X-113987Y-136784D02*
X-113113Y-135909D01*
X-112458Y-134451D01*
X-112021Y-132408D01*
X-112458Y-130659D01*
X-113331Y-129492D01*
X-114860Y-128617D01*
X-120755D01*
Y-146117D01*
X-113550D01*
X-112021Y-144951D01*
X-111148Y-143200D01*
X-110711Y-141159D01*
X-111148Y-139117D01*
X-112458Y-137367D01*
X-113987Y-136784D01*
X-120755D01*
G01X-93430Y-130076D02*
X-94740Y-129200D01*
X-96268Y-128617D01*
X-98015D01*
X-99980Y-129492D01*
X-101508Y-130950D01*
X-102600Y-132701D01*
X-103473Y-135617D01*
X-103692Y-138242D01*
X-103255Y-140867D01*
X-102600Y-142617D01*
X-101290Y-144367D01*
X-99761Y-145534D01*
X-98233Y-146117D01*
X-96705D01*
X-95176Y-145534D01*
X-93866Y-144659D01*
X-92774Y-143493D01*
G01X-67600Y-128617D02*
Y-146117D01*
X-58866D01*
G01X-41366D02*
X-50100D01*
Y-128617D01*
X-41366D01*
G01X-44860Y-137075D02*
X-50100D01*
G01X-33036Y-146117D02*
Y-128617D01*
X-28670D01*
X-26923Y-129492D01*
X-25613Y-130659D01*
X-24521Y-132408D01*
X-23648Y-134451D01*
X-23430Y-137367D01*
X-23648Y-140284D01*
X-24521Y-142326D01*
X-25613Y-144076D01*
X-26923Y-145242D01*
X-28670Y-146117D01*
X-33036D01*
G01X10260Y-135909D02*
X8732Y-134742D01*
X7422Y-134451D01*
X5675Y-135034D01*
X4365Y-136200D01*
X3492Y-138242D01*
X3273Y-140284D01*
X3492Y-142326D01*
X4365Y-144076D01*
X5675Y-145534D01*
X7422Y-146117D01*
X8950Y-145534D01*
X10260Y-144367D01*
G01X28197Y-146117D02*
Y-134451D01*
G01Y-136492D02*
X27324Y-135326D01*
X26013Y-134742D01*
X24485Y-134451D01*
X22957Y-135034D01*
X21647Y-136200D01*
X20773Y-137950D01*
X20337Y-140284D01*
X20773Y-142617D01*
X21647Y-144367D01*
X22957Y-145534D01*
X24485Y-146117D01*
X26013Y-145825D01*
X27324Y-144951D01*
X28197Y-143784D01*
G01X38710Y-146117D02*
Y-134451D01*
G01Y-136784D02*
X39802Y-135617D01*
X40894Y-134742D01*
X42422Y-134451D01*
X43513Y-134742D01*
X44824Y-135617D01*
G01X63197Y-128617D02*
Y-146117D01*
G01Y-143493D02*
X62324Y-144951D01*
X61013Y-145825D01*
X59485Y-146117D01*
X57739Y-145534D01*
X56429Y-144076D01*
X55555Y-142326D01*
X55337Y-140284D01*
X55555Y-138242D01*
X56429Y-136492D01*
X57739Y-135034D01*
X59485Y-134451D01*
X61013Y-134742D01*
X62105Y-135326D01*
X63197Y-136492D01*
G01X-77660Y-101117D02*
Y-83617D01*
X-71983Y-98200D01*
X-66306Y-83617D01*
Y-101117D01*
G01X-54483D02*
X-55793Y-100825D01*
X-57103Y-99659D01*
X-57977Y-97617D01*
X-58413Y-95284D01*
X-57977Y-92950D01*
X-57103Y-90909D01*
X-55793Y-89742D01*
X-54483Y-89451D01*
X-53173Y-89742D01*
X-51863Y-90909D01*
X-50990Y-92950D01*
X-50771Y-95284D01*
X-50990Y-97617D01*
X-51863Y-99659D01*
X-53173Y-100825D01*
X-54483Y-101117D01*
G01X-33053Y-83617D02*
Y-101117D01*
G01Y-98493D02*
X-33926Y-99951D01*
X-35237Y-100825D01*
X-36765Y-101117D01*
X-38511Y-100534D01*
X-39821Y-99076D01*
X-40695Y-97326D01*
X-40913Y-95284D01*
X-40695Y-93242D01*
X-39821Y-91492D01*
X-38511Y-90034D01*
X-36765Y-89451D01*
X-35237Y-89742D01*
X-34145Y-90326D01*
X-33053Y-91492D01*
G01X-22758Y-93242D02*
X-15771D01*
X-16426Y-91200D01*
X-17518Y-90034D01*
X-19046Y-89451D01*
X-20575Y-89742D01*
X-21885Y-90617D01*
X-22758Y-92659D01*
X-23195Y-94409D01*
Y-96159D01*
X-22758Y-97909D01*
X-21666Y-99659D01*
X-20356Y-100825D01*
X-18828Y-101117D01*
X-17300Y-100534D01*
X-15771Y-98784D01*
G01X-1983Y-101117D02*
Y-83617D01*
G01X110317Y-146117D02*
Y-128617D01*
X107697Y-132117D01*
G01Y-146117D02*
X112937D01*
G01X123669Y-138826D02*
X125197Y-136784D01*
X126507Y-135617D01*
X128254Y-135034D01*
X129782Y-135617D01*
X130874Y-136784D01*
X131747Y-138534D01*
X131965Y-140575D01*
X131747Y-142326D01*
X130874Y-144076D01*
X129563Y-145534D01*
X128035Y-146117D01*
X126289Y-145534D01*
X124760Y-143784D01*
X123887Y-141159D01*
X123669Y-138242D01*
X124105Y-134451D01*
X124760Y-132408D01*
X125852Y-130367D01*
X127380Y-128909D01*
X128909Y-128617D01*
X130437Y-129200D01*
X131529Y-130659D01*
G01X140514Y-142617D02*
X141823Y-144659D01*
X143570Y-145825D01*
X145535Y-146117D01*
X147282Y-145825D01*
X149029Y-144367D01*
X150120Y-142617D01*
X150339Y-140867D01*
X149902Y-138826D01*
X148374Y-137367D01*
X146845Y-136784D01*
X144880D01*
G01X146845D02*
X148155Y-135909D01*
X149247Y-134451D01*
X149684Y-132701D01*
X149247Y-130950D01*
X148155Y-129492D01*
X146190Y-128617D01*
X144225Y-128909D01*
X142260Y-130076D01*
G01X158669Y-138826D02*
X160197Y-136784D01*
X161507Y-135617D01*
X163254Y-135034D01*
X164782Y-135617D01*
X165874Y-136784D01*
X166747Y-138534D01*
X166965Y-140575D01*
X166747Y-142326D01*
X165874Y-144076D01*
X164563Y-145534D01*
X163035Y-146117D01*
X161289Y-145534D01*
X159760Y-143784D01*
X158887Y-141159D01*
X158669Y-138242D01*
X159105Y-134451D01*
X159760Y-132408D01*
X160852Y-130367D01*
X162380Y-128909D01*
X163909Y-128617D01*
X165437Y-129200D01*
X166529Y-130659D01*
G01X180317Y-146117D02*
X181845Y-145825D01*
X183592Y-144951D01*
X184684Y-143493D01*
X185120Y-141450D01*
X184684Y-139409D01*
X183374Y-137659D01*
X181409Y-136784D01*
X179225D01*
X177915Y-136200D01*
X176823Y-134742D01*
X176387Y-132701D01*
X177042Y-130659D01*
X178570Y-129200D01*
X180317Y-128617D01*
X182063Y-129200D01*
X183592Y-130659D01*
X184247Y-132701D01*
X183810Y-134742D01*
X182719Y-136200D01*
X181409Y-136784D01*
X179225D01*
X177260Y-137659D01*
X175950Y-139409D01*
X175514Y-141450D01*
X175950Y-143493D01*
X177042Y-144951D01*
X178789Y-145825D01*
X180317Y-146117D01*
G01X97200Y-101117D02*
Y-83617D01*
X102440D01*
X104187Y-84492D01*
X105497Y-86534D01*
X105934Y-88867D01*
X105497Y-91200D01*
X104405Y-92950D01*
X102440Y-93826D01*
X97200D01*
G01X123870Y-85076D02*
X122560Y-84200D01*
X121032Y-83617D01*
X119285D01*
X117320Y-84492D01*
X115792Y-85950D01*
X114700Y-87701D01*
X113827Y-90617D01*
X113608Y-93242D01*
X114045Y-95867D01*
X114700Y-97617D01*
X116010Y-99367D01*
X117539Y-100534D01*
X119067Y-101117D01*
X120595D01*
X122124Y-100534D01*
X123434Y-99659D01*
X124526Y-98493D01*
G01X138313Y-91784D02*
X139187Y-90909D01*
X139842Y-89451D01*
X140279Y-87408D01*
X139842Y-85659D01*
X138969Y-84492D01*
X137440Y-83617D01*
X131545D01*
Y-101117D01*
X138750D01*
X140279Y-99951D01*
X141152Y-98200D01*
X141589Y-96159D01*
X141152Y-94117D01*
X139842Y-92367D01*
X138313Y-91784D01*
X131545D01*
G01X147517Y-106950D02*
X160617D01*
G01X166545Y-101117D02*
Y-83617D01*
X176589Y-101117D01*
Y-83617D01*
G01X189067Y-101117D02*
X187320Y-100825D01*
X185792Y-99659D01*
X184482Y-97909D01*
X183608Y-95867D01*
X183172Y-93534D01*
Y-91200D01*
X183608Y-88867D01*
X184482Y-86825D01*
X185792Y-85076D01*
X187320Y-83909D01*
X189067Y-83617D01*
X190813Y-83909D01*
X192342Y-85076D01*
X193652Y-86825D01*
X194526Y-88867D01*
X194962Y-91200D01*
Y-93534D01*
X194526Y-95867D01*
X193652Y-97909D01*
X192342Y-99659D01*
X190813Y-100825D01*
X189067Y-101117D01*
G01X258282Y-143784D02*
X260029Y-145242D01*
X261994Y-146117D01*
X263740D01*
X265487Y-145242D01*
X266797Y-143784D01*
X267452Y-141742D01*
X267015Y-139701D01*
X265924Y-137950D01*
X263959Y-136784D01*
X261339Y-136200D01*
X259810Y-135034D01*
X259155Y-132992D01*
X259592Y-130950D01*
X260684Y-129492D01*
X262212Y-128617D01*
X263740D01*
X265269Y-129200D01*
X266579Y-130659D01*
G01X282113Y-136784D02*
X282987Y-135909D01*
X283642Y-134451D01*
X284079Y-132408D01*
X283642Y-130659D01*
X282769Y-129492D01*
X281240Y-128617D01*
X275345D01*
Y-146117D01*
X282550D01*
X284079Y-144951D01*
X284952Y-143200D01*
X285389Y-141159D01*
X284952Y-139117D01*
X283642Y-137367D01*
X282113Y-136784D01*
X275345D01*
G01X239908Y-83617D02*
X245367Y-101117D01*
X250826Y-83617D01*
G01X267234Y-101117D02*
X258500D01*
Y-83617D01*
X267234D01*
G01X263740Y-92075D02*
X258500D01*
G01X276000Y-101117D02*
Y-83617D01*
X281459D01*
X283205Y-84492D01*
X284297Y-85659D01*
X284734Y-87992D01*
X284297Y-90326D01*
X282987Y-91784D01*
X281459Y-92659D01*
X276000D01*
G01X281459D02*
X284734Y-101117D01*
G01X297867Y-101700D02*
X297430Y-101409D01*
Y-100825D01*
X297867Y-100534D01*
X298304Y-100825D01*
Y-101409D01*
X297867Y-101700D01*
G01X446071Y-136784D02*
X445197Y-135909D01*
X444542Y-134451D01*
X444105Y-132408D01*
X444542Y-130659D01*
X445415Y-129492D01*
X446944Y-128617D01*
X452839D01*
Y-146117D01*
X445634D01*
X444105Y-144951D01*
X443232Y-143200D01*
X442795Y-141159D01*
X443232Y-139117D01*
X444542Y-137367D01*
X446071Y-136784D01*
X452839D01*
G01X434902Y-143784D02*
X433155Y-145242D01*
X431190Y-146117D01*
X429444D01*
X427697Y-145242D01*
X426387Y-143784D01*
X425732Y-141742D01*
X426169Y-139701D01*
X427260Y-137950D01*
X429225Y-136784D01*
X431845Y-136200D01*
X433374Y-135034D01*
X434029Y-132992D01*
X433592Y-130950D01*
X432500Y-129492D01*
X430972Y-128617D01*
X429444D01*
X427915Y-129200D01*
X426605Y-130659D01*
G01X415437Y-128617D02*
X410197D01*
G01X412817D02*
Y-146117D01*
G01X415437D02*
X410197D01*
G01X399684Y-128617D02*
Y-146117D01*
X390950D01*
G01X382620D02*
Y-128617D01*
G01X374324D02*
X382620Y-139409D01*
G01X373014Y-146117D02*
X378909Y-134451D01*
G01X373450Y-83617D02*
Y-101117D01*
X382184D01*
G01X399247D02*
Y-89451D01*
G01Y-91492D02*
X398374Y-90326D01*
X397063Y-89742D01*
X395535Y-89451D01*
X394007Y-90034D01*
X392697Y-91200D01*
X391823Y-92950D01*
X391387Y-95284D01*
X391823Y-97617D01*
X392697Y-99367D01*
X394007Y-100534D01*
X395535Y-101117D01*
X397063Y-100825D01*
X398374Y-99951D01*
X399247Y-98784D01*
G01X408232Y-106367D02*
X409542Y-106950D01*
X411289Y-106367D01*
X412380Y-105201D01*
X413254Y-103742D01*
X414563Y-99076D01*
X417402Y-89451D01*
G01X410415D02*
X414563Y-99076D01*
G01X427042Y-93242D02*
X434029D01*
X433374Y-91200D01*
X432282Y-90034D01*
X430754Y-89451D01*
X429225Y-89742D01*
X427915Y-90617D01*
X427042Y-92659D01*
X426605Y-94409D01*
Y-96159D01*
X427042Y-97909D01*
X428134Y-99659D01*
X429444Y-100825D01*
X430972Y-101117D01*
X432500Y-100534D01*
X434029Y-98784D01*
G01X444760Y-101117D02*
Y-89451D01*
G01Y-91784D02*
X445852Y-90617D01*
X446944Y-89742D01*
X448472Y-89451D01*
X449563Y-89742D01*
X450874Y-90617D01*
G01X515564Y-101117D02*
Y-83617D01*
X519930D01*
X521677Y-84492D01*
X522987Y-85659D01*
X524079Y-87408D01*
X524952Y-89451D01*
X525170Y-92367D01*
X524952Y-95284D01*
X524079Y-97326D01*
X522987Y-99076D01*
X521677Y-100242D01*
X519930Y-101117D01*
X515564D01*
G01X534592Y-93242D02*
X541579D01*
X540924Y-91200D01*
X539832Y-90034D01*
X538304Y-89451D01*
X536775Y-89742D01*
X535465Y-90617D01*
X534592Y-92659D01*
X534155Y-94409D01*
Y-96159D01*
X534592Y-97909D01*
X535684Y-99659D01*
X536994Y-100825D01*
X538522Y-101117D01*
X540050Y-100534D01*
X541579Y-98784D01*
G01X552092Y-99076D02*
X553184Y-100242D01*
X554712Y-101117D01*
X556022D01*
X557332Y-100534D01*
X558205Y-99659D01*
X558642Y-98493D01*
X558424Y-96742D01*
X557550Y-95867D01*
X553620Y-94117D01*
X552747Y-92075D01*
X553184Y-90617D01*
X554057Y-89742D01*
X555367Y-89451D01*
X556677Y-89742D01*
X557987Y-90617D01*
G01X572867Y-89451D02*
Y-101117D01*
G01Y-84784D02*
X572430Y-84492D01*
Y-83909D01*
X572867Y-83617D01*
X573304Y-83909D01*
Y-84492D01*
X572867Y-84784D01*
G01X587310Y-105492D02*
X588839Y-106659D01*
X590585Y-106950D01*
X592113Y-106659D01*
X593424Y-105201D01*
X594297Y-103159D01*
Y-89451D01*
G01Y-91784D02*
X593424Y-90617D01*
X592113Y-89742D01*
X590585Y-89451D01*
X588839Y-90034D01*
X587747Y-91200D01*
X586873Y-93242D01*
X586437Y-95284D01*
X586655Y-97034D01*
X587529Y-99076D01*
X588839Y-100534D01*
X590585Y-101117D01*
X591895Y-100825D01*
X593424Y-99659D01*
X594297Y-98493D01*
G01X604155Y-101117D02*
Y-89451D01*
G01Y-92367D02*
X605029Y-90909D01*
X606339Y-89742D01*
X608085Y-89451D01*
X609613Y-89742D01*
X610924Y-90909D01*
X611579Y-92950D01*
Y-101117D01*
G01X622092Y-93242D02*
X629079D01*
X628424Y-91200D01*
X627332Y-90034D01*
X625804Y-89451D01*
X624275Y-89742D01*
X622965Y-90617D01*
X622092Y-92659D01*
X621655Y-94409D01*
Y-96159D01*
X622092Y-97909D01*
X623184Y-99659D01*
X624494Y-100825D01*
X626022Y-101117D01*
X627550Y-100534D01*
X629079Y-98784D01*
G01X639810Y-101117D02*
Y-89451D01*
G01Y-91784D02*
X640902Y-90617D01*
X641994Y-89742D01*
X643522Y-89451D01*
X644613Y-89742D01*
X645924Y-90617D01*
G01X559969Y-128617D02*
X568265D01*
X559969Y-146117D01*
X568265D01*
G01X581617D02*
X579870Y-145825D01*
X578342Y-144659D01*
X577032Y-142909D01*
X576158Y-140867D01*
X575722Y-138534D01*
Y-136200D01*
X576158Y-133867D01*
X577032Y-131825D01*
X578342Y-130076D01*
X579870Y-128909D01*
X581617Y-128617D01*
X583363Y-128909D01*
X584892Y-130076D01*
X586202Y-131825D01*
X587076Y-133867D01*
X587512Y-136200D01*
Y-138534D01*
X587076Y-140867D01*
X586202Y-142909D01*
X584892Y-144659D01*
X583363Y-145825D01*
X581617Y-146117D01*
G01X603484D02*
X594750D01*
Y-128617D01*
X603484D01*
G01X599990Y-137075D02*
X594750D01*
G01X686567Y-128617D02*
X684820Y-129200D01*
X683510Y-130659D01*
X682637Y-132408D01*
X681982Y-134742D01*
X681764Y-137367D01*
X681982Y-139992D01*
X682637Y-142326D01*
X683510Y-144076D01*
X684820Y-145534D01*
X686567Y-146117D01*
X688313Y-145534D01*
X689624Y-144076D01*
X690497Y-142326D01*
X691152Y-139992D01*
X691370Y-137367D01*
X691152Y-134742D01*
X690497Y-132408D01*
X689624Y-130659D01*
X688313Y-129200D01*
X686567Y-128617D01*
G01X699919Y-131534D02*
X701229Y-129784D01*
X702757Y-128909D01*
X704504Y-128617D01*
X706687Y-129200D01*
X708215Y-130659D01*
X708652Y-132408D01*
X708434Y-134159D01*
X707560Y-135617D01*
X703194Y-138534D01*
X701229Y-140575D01*
X699919Y-143493D01*
X699482Y-146117D01*
X708652D01*
G01X717637Y-146700D02*
X725497Y-128617D01*
G01X739067D02*
X737320Y-129200D01*
X736010Y-130659D01*
X735137Y-132408D01*
X734482Y-134742D01*
X734264Y-137367D01*
X734482Y-139992D01*
X735137Y-142326D01*
X736010Y-144076D01*
X737320Y-145534D01*
X739067Y-146117D01*
X740813Y-145534D01*
X742124Y-144076D01*
X742997Y-142326D01*
X743652Y-139992D01*
X743870Y-137367D01*
X743652Y-134742D01*
X742997Y-132408D01*
X742124Y-130659D01*
X740813Y-129200D01*
X739067Y-128617D01*
G01X756130Y-146117D02*
X756567Y-142326D01*
X757222Y-139117D01*
X758095Y-136200D01*
X759187Y-132992D01*
X760934Y-128617D01*
X752200D01*
G01X770137Y-146700D02*
X777997Y-128617D01*
G01X787419Y-131534D02*
X788729Y-129784D01*
X790257Y-128909D01*
X792004Y-128617D01*
X794187Y-129200D01*
X795715Y-130659D01*
X796152Y-132408D01*
X795934Y-134159D01*
X795060Y-135617D01*
X790694Y-138534D01*
X788729Y-140575D01*
X787419Y-143493D01*
X786982Y-146117D01*
X796152D01*
G01X809067Y-128617D02*
X807320Y-129200D01*
X806010Y-130659D01*
X805137Y-132408D01*
X804482Y-134742D01*
X804264Y-137367D01*
X804482Y-139992D01*
X805137Y-142326D01*
X806010Y-144076D01*
X807320Y-145534D01*
X809067Y-146117D01*
X810813Y-145534D01*
X812124Y-144076D01*
X812997Y-142326D01*
X813652Y-139992D01*
X813870Y-137367D01*
X813652Y-134742D01*
X812997Y-132408D01*
X812124Y-130659D01*
X810813Y-129200D01*
X809067Y-128617D01*
G01X826567Y-146117D02*
Y-128617D01*
X823947Y-132117D01*
G01Y-146117D02*
X829187D01*
G01X843630D02*
X844067Y-142326D01*
X844722Y-139117D01*
X845595Y-136200D01*
X846687Y-132992D01*
X848434Y-128617D01*
X839700D01*
G01X734264Y-101117D02*
Y-83617D01*
X738630D01*
X740377Y-84492D01*
X741687Y-85659D01*
X742779Y-87408D01*
X743652Y-89451D01*
X743870Y-92367D01*
X743652Y-95284D01*
X742779Y-97326D01*
X741687Y-99076D01*
X740377Y-100242D01*
X738630Y-101117D01*
X734264D01*
G01X760497D02*
Y-89451D01*
G01Y-91492D02*
X759624Y-90326D01*
X758313Y-89742D01*
X756785Y-89451D01*
X755257Y-90034D01*
X753947Y-91200D01*
X753073Y-92950D01*
X752637Y-95284D01*
X753073Y-97617D01*
X753947Y-99367D01*
X755257Y-100534D01*
X756785Y-101117D01*
X758313Y-100825D01*
X759624Y-99951D01*
X760497Y-98784D01*
G01X774067Y-83617D02*
Y-101117D01*
G01X771010Y-89451D02*
X777124D01*
G01X788292Y-93242D02*
X795279D01*
X794624Y-91200D01*
X793532Y-90034D01*
X792004Y-89451D01*
X790475Y-89742D01*
X789165Y-90617D01*
X788292Y-92659D01*
X787855Y-94409D01*
Y-96159D01*
X788292Y-97909D01*
X789384Y-99659D01*
X790694Y-100825D01*
X792222Y-101117D01*
X793750Y-100534D01*
X795279Y-98784D01*
G01X89553Y58698D02*
Y29098D01*
X141353D01*
Y58698D01*
X89553D01*
G01X63933Y26000D02*
Y28500D01*
X62892D01*
X62558Y28375D01*
X62350Y28208D01*
X62267Y27875D01*
X62350Y27542D01*
X62600Y27333D01*
X62892Y27208D01*
X63933D01*
G01X62892D02*
X62267Y26000D01*
G01X60000D02*
Y28500D01*
X60500Y28000D01*
G01Y26000D02*
X59500D01*
G01X56983D02*
X56900Y26542D01*
X56775Y27000D01*
X56608Y27417D01*
X56400Y27875D01*
X56067Y28500D01*
X57733D01*
G01X72300Y29500D02*
Y25500D01*
X64900D01*
G01X71433Y30500D02*
Y33000D01*
X70392D01*
X70058Y32875D01*
X69850Y32708D01*
X69767Y32375D01*
X69850Y32042D01*
X70100Y31833D01*
X70392Y31708D01*
X71433D01*
G01X70392D02*
X69767Y30500D01*
G01X67500D02*
Y33000D01*
X68000Y32500D01*
G01Y30500D02*
X67000D01*
G01X64400Y33000D02*
X64733Y32917D01*
X64983Y32708D01*
X65150Y32458D01*
X65275Y32125D01*
X65317Y31750D01*
X65275Y31375D01*
X65150Y31042D01*
X64983Y30792D01*
X64733Y30583D01*
X64400Y30500D01*
X64067Y30583D01*
X63817Y30792D01*
X63650Y31042D01*
X63525Y31375D01*
X63483Y31750D01*
X63525Y32125D01*
X63650Y32458D01*
X63817Y32708D01*
X64067Y32917D01*
X64400Y33000D01*
G01X72500Y33200D02*
X76500D01*
Y25800D01*
G01X95183Y24792D02*
X95433Y24917D01*
X95725Y25000D01*
X96058D01*
X96433Y24875D01*
X96725Y24667D01*
X96933Y24417D01*
X97100Y24000D01*
X97142Y23625D01*
X97058Y23250D01*
X96933Y23000D01*
X96683Y22750D01*
X96392Y22583D01*
X96100Y22500D01*
X95808D01*
X95517Y22583D01*
X95267Y22708D01*
X95058Y22875D01*
G01X93958Y22500D02*
Y25000D01*
X92042Y22500D01*
Y25000D01*
G01X89900Y22500D02*
Y25000D01*
X90400Y24500D01*
G01Y22500D02*
X89400D01*
G01X58035Y24242D02*
Y20742D01*
X37535D01*
Y1942D01*
X108135D01*
Y20742D01*
X87635D01*
Y24242D01*
X58035D01*
G01X77500Y41200D02*
Y27800D01*
G01X87500D02*
Y41200D01*
G01X77500Y27800D02*
X87500D01*
G01X121433Y2000D02*
Y4500D01*
X120433D01*
X120100Y4375D01*
X119850Y4083D01*
X119767Y3750D01*
X119850Y3417D01*
X120058Y3167D01*
X120433Y3042D01*
X121433D01*
G01X117500Y2000D02*
X117833Y2042D01*
X118125Y2208D01*
X118375Y2458D01*
X118542Y2750D01*
X118625Y3083D01*
Y3417D01*
X118542Y3750D01*
X118375Y4042D01*
X118125Y4292D01*
X117833Y4458D01*
X117500Y4500D01*
X117167Y4458D01*
X116875Y4292D01*
X116625Y4042D01*
X116458Y3750D01*
X116375Y3417D01*
Y3083D01*
X116458Y2750D01*
X116625Y2458D01*
X116875Y2208D01*
X117167Y2042D01*
X117500Y2000D01*
G01X117167Y2667D02*
X116667Y2000D01*
G01X114400D02*
Y4500D01*
X114900Y4000D01*
G01Y2000D02*
X113900D01*
G01X110650Y15950D02*
Y6050D01*
G01X124350Y15950D02*
X110650D01*
G01Y6050D02*
X124350D01*
G01X106933Y23000D02*
Y25500D01*
X105933D01*
X105600Y25375D01*
X105350Y25083D01*
X105267Y24750D01*
X105350Y24417D01*
X105558Y24167D01*
X105933Y24042D01*
X106933D01*
G01X103833Y23000D02*
Y25500D01*
X102792D01*
X102458Y25375D01*
X102250Y25208D01*
X102167Y24875D01*
X102250Y24542D01*
X102500Y24333D01*
X102792Y24208D01*
X103833D01*
G01X102792D02*
X102167Y23000D01*
G01X99900D02*
Y25500D01*
X100400Y25000D01*
G01Y23000D02*
X99400D01*
G01X60500Y46067D02*
X63000D01*
Y47108D01*
X62875Y47442D01*
X62708Y47650D01*
X62375Y47733D01*
X62042Y47650D01*
X61833Y47400D01*
X61708Y47108D01*
Y46067D01*
G01Y47108D02*
X60500Y47733D01*
G01Y50000D02*
X63000D01*
X62500Y49500D01*
G01X60500D02*
Y50500D01*
G01Y53100D02*
X60542Y53392D01*
X60667Y53725D01*
X60875Y53933D01*
X61167Y54017D01*
X61458Y53933D01*
X61708Y53683D01*
X61833Y53308D01*
Y52892D01*
X61917Y52642D01*
X62125Y52433D01*
X62417Y52350D01*
X62708Y52475D01*
X62917Y52767D01*
X63000Y53100D01*
X62917Y53433D01*
X62708Y53725D01*
X62417Y53850D01*
X62125Y53767D01*
X61917Y53558D01*
X61833Y53308D01*
Y52892D01*
X61708Y52517D01*
X61458Y52267D01*
X61167Y52183D01*
X60875Y52267D01*
X60667Y52475D01*
X60542Y52808D01*
X60500Y53100D01*
G01X68000Y53700D02*
X72000D01*
Y46300D01*
G01X64500Y46067D02*
X67000D01*
Y47108D01*
X66875Y47442D01*
X66708Y47650D01*
X66375Y47733D01*
X66042Y47650D01*
X65833Y47400D01*
X65708Y47108D01*
Y46067D01*
G01Y47108D02*
X64500Y47733D01*
G01Y50000D02*
X67000D01*
X66500Y49500D01*
G01X64500D02*
Y50500D01*
G01X66583Y52308D02*
X66833Y52558D01*
X66958Y52850D01*
X67000Y53183D01*
X66917Y53600D01*
X66708Y53892D01*
X66458Y53975D01*
X66208Y53933D01*
X66000Y53767D01*
X65583Y52933D01*
X65292Y52558D01*
X64875Y52308D01*
X64500Y52225D01*
Y53975D01*
G01X76000Y46300D02*
X72000D01*
Y53700D01*
G01X84967Y61000D02*
Y59208D01*
X84800Y58833D01*
X84467Y58583D01*
X84050Y58500D01*
X83633Y58583D01*
X83300Y58833D01*
X83133Y59208D01*
Y61000D01*
G01X81742Y59542D02*
X81450Y59833D01*
X81200Y60000D01*
X80867Y60083D01*
X80575Y60000D01*
X80367Y59833D01*
X80200Y59583D01*
X80158Y59292D01*
X80200Y59042D01*
X80367Y58792D01*
X80617Y58583D01*
X80908Y58500D01*
X81242Y58583D01*
X81533Y58833D01*
X81700Y59208D01*
X81742Y59625D01*
X81658Y60167D01*
X81533Y60458D01*
X81325Y60750D01*
X81033Y60958D01*
X80742Y61000D01*
X80450Y60917D01*
X80242Y60708D01*
G01X87500Y43300D02*
Y56700D01*
G01X77500Y43300D02*
X87500D01*
G01X77500Y56700D02*
Y43300D01*
G01X87500Y56700D02*
X77500D01*
G01X75467Y38500D02*
Y36708D01*
X75300Y36333D01*
X74967Y36083D01*
X74550Y36000D01*
X74133Y36083D01*
X73800Y36333D01*
X73633Y36708D01*
Y38500D01*
G01X72367Y36375D02*
X72117Y36167D01*
X71825Y36042D01*
X71450Y36000D01*
X71075Y36083D01*
X70783Y36250D01*
X70575Y36542D01*
X70533Y36875D01*
X70617Y37208D01*
X70825Y37417D01*
X71117Y37583D01*
X71408Y37625D01*
X71700Y37583D01*
X72075Y37417D01*
X71950Y38500D01*
X70825D01*
G01X87500Y41200D02*
X77500D01*
G01X133933Y3000D02*
Y5500D01*
X132933D01*
X132600Y5375D01*
X132350Y5083D01*
X132267Y4750D01*
X132350Y4417D01*
X132558Y4167D01*
X132933Y4042D01*
X133933D01*
G01X129083Y5292D02*
X129333Y5417D01*
X129625Y5500D01*
X129958D01*
X130333Y5375D01*
X130625Y5167D01*
X130833Y4917D01*
X131000Y4500D01*
X131042Y4125D01*
X130958Y3750D01*
X130833Y3500D01*
X130583Y3250D01*
X130292Y3083D01*
X130000Y3000D01*
X129708D01*
X129417Y3083D01*
X129167Y3208D01*
X128958Y3375D01*
G01X127692Y5083D02*
X127442Y5333D01*
X127150Y5458D01*
X126817Y5500D01*
X126400Y5417D01*
X126108Y5208D01*
X126025Y4958D01*
X126067Y4708D01*
X126233Y4500D01*
X127067Y4083D01*
X127442Y3792D01*
X127692Y3375D01*
X127775Y3000D01*
X126025D01*
G01X133500Y7067D02*
X136000D01*
Y8067D01*
X135875Y8400D01*
X135583Y8650D01*
X135250Y8733D01*
X134917Y8650D01*
X134667Y8442D01*
X134542Y8067D01*
Y7067D01*
G01X135792Y11917D02*
X135917Y11667D01*
X136000Y11375D01*
Y11042D01*
X135875Y10667D01*
X135667Y10375D01*
X135417Y10167D01*
X135000Y10000D01*
X134625Y9958D01*
X134250Y10042D01*
X134000Y10167D01*
X133750Y10417D01*
X133583Y10708D01*
X133500Y11000D01*
Y11292D01*
X133583Y11583D01*
X133708Y11833D01*
X133875Y12042D01*
G01X133500Y14100D02*
X136000D01*
X135500Y13600D01*
G01X133500D02*
Y14600D01*
G01X124350Y6050D02*
Y15950D01*
G01X131433Y25500D02*
Y28000D01*
X130433D01*
X130100Y27875D01*
X129850Y27583D01*
X129767Y27250D01*
X129850Y26917D01*
X130058Y26667D01*
X130433Y26542D01*
X131433D01*
G01X128417Y25500D02*
Y28000D01*
X127583D01*
X127250Y27875D01*
X127000Y27708D01*
X126792Y27458D01*
X126625Y27167D01*
X126583Y26750D01*
X126625Y26333D01*
X126792Y26042D01*
X127000Y25792D01*
X127250Y25625D01*
X127583Y25500D01*
X128417D01*
G01X124400D02*
Y28000D01*
X124900Y27500D01*
G01Y25500D02*
X123900D01*
G01X119000Y17500D02*
X135100D01*
G01X119000Y24500D02*
Y17500D01*
G01X135100Y24500D02*
X119000D01*
G01X135100Y17500D02*
Y24500D01*
G01X149683Y57292D02*
X149933Y57417D01*
X150225Y57500D01*
X150558D01*
X150933Y57375D01*
X151225Y57167D01*
X151433Y56917D01*
X151600Y56500D01*
X151642Y56125D01*
X151558Y55750D01*
X151433Y55500D01*
X151183Y55250D01*
X150892Y55083D01*
X150600Y55000D01*
X150308D01*
X150017Y55083D01*
X149767Y55208D01*
X149558Y55375D01*
G01X148458Y55000D02*
Y57500D01*
X146542Y55000D01*
Y57500D01*
G01X145192Y57083D02*
X144942Y57333D01*
X144650Y57458D01*
X144317Y57500D01*
X143900Y57417D01*
X143608Y57208D01*
X143525Y56958D01*
X143567Y56708D01*
X143733Y56500D01*
X144567Y56083D01*
X144942Y55792D01*
X145192Y55375D01*
X145275Y55000D01*
X143525D01*
G54D14*
G01X113000Y23300D02*
Y22200D01*
G01Y26000D02*
Y24900D01*
M02*
